FILE_TYPE = CONNECTIVITY;
{Allegro Design Entry HDL 16.6-p007 (v16-6-112F) 10/10/2012}
"PAGE_NUMBER" = 147;
0"NC";
1"GND\g";
2"GND\g";
3"GND\g";
4"VCC_ADCAV3V3\g"VOLTAGE"+3.3V"CDS_PHYS_NET_NAME"P3V3_STBY_BMC_ADCAV33";
5"GND\g";
6"GND\g";
7"P3V3_STBY\g";
8"GND\g";
9"GND\g";
10"GND\g";
11"GND\g";
12"GND\g";
13"RMII_BMC_OCP_TXD0_R";
14"A_P5V_SCALED";
15"P3V3_STBY_BMC_ADCVREFN"VOLTAGE"+3.3V";
16"FM_BMC_FAULT_LED_N"CDS_PHYS_NET_NAME"FM_BMC_FAULT_LED_N";
17"A_P1V05_STBY_PCH_SENSOR";
18"FM_FLASH_DESC_OVERRIDE"CDS_PHYS_NET_NAME"FM_FLASH_DESC_OVERRIDE";
19"RMII_BMC_OCP_TXEN";
20"RMII_BMC_PCH_SPRNGVLLE_TXD1";
21"RMII_BMC_PCH_SPRNGVLLE_TXEN";
22"PD_ADCREXT"CDS_PHYS_NET_NAME"PD_ADCREXT";
23"FM_BB_BMC_MP_GPIO";
24"FM_BMC_CPLD_MP_RST_N"CDS_PHYS_NET_NAME"FM_BMC_CPLD_MP_RST_N";
25"PUMP_PWM_OUT";
26"FM_PWRBRK_N";
27"FM_BACKUP_BIOS_SEL_N";
28"FM_BIOS_SPI_BMC_CTRL"CDS_PHYS_NET_NAME"FM_BIOS_SPI_BMC_CTRL";
29"FM_CPU_MSMI_LVT3_N";
30"FAN_PWM_OUT_SYS1";
31"FM_BIOS_PREFRB2_GOOD";
32"FAN_PWM_OUT_SYS0";
33"P3V3_STBY_BMC_ADCVREFP"VOLTAGE"+3.3V";
34"H_CPU1_MEMGHJ_MEMHOT_LVT3_BMC_N";
35"H_CPU1_MEMKLM_MEMHOT_LVT3_BMC_N";
36"H_CPU0_MEMDEF_MEMHOT_LVT3_BMC_N";
37"H_CPU0_MEMABC_MEMHOT_LVT3_BMC_N";
38"A_P5V_STBY_SCALED";
39"A_PVNN_STBY_PCH_SENSOR";
40"A_P3V3_STBY_SCALED";
41"A_P12V_STBY_SCALED";
42"A_P3V3_SCALED";
43"RMII_BMC_SPRNGVLLE_TXEN_R";
44"TP_RGMII2TXD2_GPIOU2";
45"TP_RGMII2TXD3_GPIOU3";
46"RMII_BMC_PCH_SPRNGVLLE_TXD1_R";
47"RMII_BMC_PCH_SPRNGVLLE_TXD0_R";
48"RMII_BMC_OCP_TXEN_R";
49"FM_FAST_PROCHOT_EN_N"CDS_PHYS_NET_NAME"FM_FAST_PROCHOT_EN_N";
50"RMII_BMC_OCP_RXD1";
51"CLK_50M_CKMNG_BMC_1"CDS_PHYS_NET_NAME"CLK_50M_CKMNG_BMC_1"$PHYS_NET_NAME"CLK_50M_CKMNG_BMC_1";
52"RMII_SPRNGVLLE_BMC_PCH_RXD0";
53"RMII_SPRNGVLLE_BMC_PCH_RXD1";
54"RMII_BMC_PCH_SPRNGVLLE_CRSDV";
55"RMII_BMC_PCH_SPRNGVLLE_RXER";
56"CLK_50M_CKMNG_BMC_2"CDS_PHYS_NET_NAME"CLK_50M_CKMNG_BMC_2"$PHYS_NET_NAME"CLK_50M_CKMNG_BMC_2";
57"A_P3V_BAT_SCALED";
58"RMII_BMC_OCP_CRSDV";
59"RMII_BMC_OCP_RXER";
60"FM_BOARD_SKU_ID4";
61"FM_BOARD_SKU_ID0";
62"FM_XRC_READY_N";
63"FM_XRC_PRESENT_N";
64"RMII_BMC_OCP_RXD0";
65"BMC_RSMRST_B_N";
66"BMC_PREQ_N"CDS_PHYS_NET_NAME"BMC_PREQ_N";
67"BMC_PWR_DEBUG_N";
68"RST_RSMRST_N";
69"FM_SLT_CFG0";
70"FM_SLT_CFG1";
71"FM_BOARD_SKU_ID3";
72"FM_BOARD_SKU_ID2";
73"FM_BOARD_SKU_ID1";
74"PUMP_TACH1";
75"FAN_TACH3";
76"FAN_TACH2";
77"FAN_TACH1";
78"PUMP_TACH0";
79"FAN_TACH0";
80"TP_RGMII1TXD3_GPIOT5";
81"TP_RGMII1TXD2_GPIOT4";
82"RMII_BMC_OCP_TXD1";
83"RMII_BMC_OCP_TXD0";
84"RMII_BMC_OCP_TXD1_R";
85"FM_GLOBAL_RST_WARN_N_R";
86"FM_GLOBAL_RST_WARN_N";
87"RMII_BMC_PCH_SPRNGVLLE_TXD0";
%"AST2520A1-GP-GP"
"6","(-1825,3400)","0","w_hdl","I106";
;
CDS_SEC"6"
CDS_LOCATION"U25W4"
LOCATION"U25W4"
VALUE"AST2520A1-GP-GP"
CDS_LIB"w_hdl"
PART_NUMBER"071.2520A.M001"
CDS_LMAN_SYM_OUTLINE"-1400,1400,1400,-1400"
PACK_TYPE"ASIC2-GB1"
SEC"6"
SEC_TYPE"ASIC2-GB1";
"RGMII2RXCK_RMII2RCLKI_GPIOV2"
$PN"C2"56;
"RGMII2RXD3_RMII2RXER_GPIOV7"
$PN"E6"55;
"RGMII2RXD2_RMII2CRSDV_GPIOV6"
$PN"D2"54;
"RGMII2RXD1_RMII2RXD1_GPIOV5"
$PN"D1"53;
"RGMII2RXD0_RMII2RXD0_GPIOV4"
$PN"C3"52;
"RGMII1RXCK_RMII1RCLKI_GPIOU4"
$PN"B4"51;
"RGMII1RXCTL_GPIOU5"
$PN"A4"16;
"RGMII1RXD3_RMII1RXER_GPIOV1"
$PN"C4"59;
"RGMII1RXD2_RMII1CRSDV_GPIOV0"
$PN"C5"58;
"RGMII1RXD1_RMII1RXD1_GPIOU7"
$PN"D6"50;
"RGMII1RXD0_RMII1RXD0_GPIOU6"
$PN"A3"64;
"GPIOR7_MDIO1"
$PN"E10"70;
"GPIOR6_MDC1"
$PN"D8"69;
"RGMII2RXCTL_GPIOV3"
$PN"C1"49;
"RGMII1TXD1_RMII1TXD1_GPIOT3"
$PN"A5"84;
"RGMII1TXD0_RMII1TXD0_GPIOT2"
$PN"F9"13;
"RGMII1TXD3_GPIOT5"
$PN"D7"80;
"RGMII1TXD2_GPIOT4"
$PN"E7"81;
"RGMII1TXCTL_RMII1TXEN_GPIOT1"
$PN"E9"48;
"RGMII1TXCK_RMII1RCLKO_GPIOT0"
$PN"B5"0;
"RGMII2TXD0_RMII2TXD0_GPIOU0"
$PN"A2"47;
"RGMII2TXD1_RMII2TXD1_GPIOU1"
$PN"B3"46;
"RGMII2TXD3_GPIOU3"
$PN"D4"45;
"RGMII2TXD2_GPIOU2"
$PN"D5"44;
"RGMII2TXCK_RMII2RCLKO_GPIOT6"
$PN"B2"0;
"RGMII2TXCTL_RMII2TXEN_GPIOT7"
$PN"B1"43;
"GPIOO0_TACH0_VPIG8"
$PN"U5"79;
"GPIOO2_TACH2"
$PN"V5"76;
"GPIOO1_TACH1_VPIG9"
$PN"U4"77;
"GPIOO3_TACH3"
$PN"AB4"75;
"GPIOO5_TACH5_VPIR3"
$PN"Y4"74;
"GPIOO4_TACH4_VPIR2"
$PN"AB3"78;
"GPIOP0_TACH8_VPIR6"
$PN"V4"61;
"GPIOO7_TACH7_VPIR5"
$PN"W4"62;
"GPIOO6_TACH6_VPIR4"
$PN"AA4"63;
"GPIOP1_TACH9_VPIR7"
$PN"W5"73;
"GPIOP2_TACH10_VPIR8"
$PN"AA5"72;
"GPIOP5_TACH13"
$PN"Y5"66;
"GPIOP4_TACH12"
$PN"Y6"60;
"GPIOP3_TACH11_VPIR9"
$PN"AB5"71;
"GPIOP6_TACH14"
$PN"W6"67;
"GPIOP7_TACH15"
$PN"V6"65;
"ADC0_GPIW0"
$PN"F4"42;
"ADC1_GPIW1"
$PN"F5"14;
"ADC2_GPIW2"
$PN"E2"41;
"ADC3_GPIW3"
$PN"E1"17;
"ADC5_GPIW5"
$PN"E3"40;
"ADC4_GPIW4"
$PN"F3"39;
"ADC6_GPIW6"
$PN"G5"38;
"ADC10_GPIX2"
$PN"G2"1;
"ADC9_GPIX1"
$PN"G3"1;
"ADC11_GPIX3"
$PN"F1"85;
"ADC12_GPIX4"
$PN"H5"37;
"ADC13_GPIX5"
$PN"G1"36;
"ADC15_GPIX7"
$PN"H4"35;
"ADC14_GPIX6"
$PN"H3"34;
"ADCVREFN"
$PN"H1"15;
"ADCREXT"
$PN"J1"22;
"ADCVREFP"
$PN"H2"33;
"GPION0_PWM0"
$PN"V2"32;
"GPION2_PWM2_VPIG2"
$PN"V3"31;
"GPION1_PWM1"
$PN"W2"30;
"GPION3_PWM3_VPIG3"
$PN"U3"29;
"GPION5_PWM5_VPIG5"
$PN"AA3"28;
"GPION4_PWM4_VPIG4"
$PN"W3"27;
"GPION7_PWM7_VPIG7"
$PN"T4"26;
"GPION6_PWM6_VPIG6"
$PN"Y3"25;
"RGMIICK"
$PN"D3"0;
"GPIOA7_TIMER8_MDIO2"
$PN"B13"24;
"GPIOA6_TIMER7_MDC2"
$PN"C13"23;
"ADC7_GPIW7"
$PN"G4"57;
"ADC8_GPIX0"
$PN"F2"1;
%"RES"
"1","(-4100,1500)","0","mstr_discrete","I129";
;
PACK_TYPE"0402"
LOCATION"R1T24"
VALUE"0.0"
WATTAGE"1/16W"
PART_NUMBER"G21497-005"
TOLERANCE"5%"
MATERIAL"EMPTY"
CDS_SEC"1"
CDS_LIB"mstr_discrete"
CDS_LOCATION"R1T24"
SEC"1"
SEC_TYPE"0402";
"B"
$PN"2"18;
"A"
$PN"1"78;
%"GND"
"1","(100,3350)","1","mstr_symbols","I145";
;
VOLTAGE"0.0V"
SIZE"1B"
CDS_LIB"mstr_symbols"
BODY_TYPE"PLUMBING"
HDL_POWER"GND";
"A\NAC"1;
%"RES"
"2","(900,1950)","0","mstr_discrete","I151";
;
CDS_SEC"1"
CDS_LOCATION"R25W57"
MATERIAL"CHIP"
WATTAGE"1/16W"
PART_NUMBER"G21796-048"
PACK_TYPE"0402"
TOLERANCE"1%"
VALUE"49.9K"
LOCATION"R25W57"
SEC"1"
SEC_TYPE"0402"
ROOM"V_SUPER"
CDS_LIB"mstr_discrete";
"A"
$PN"1"22;
"B"
$PN"2"6;
%"RES"
"2","(-4700,1950)","0","mstr_discrete","I156";
;
CDS_SEC"1"
WATTAGE"1/16W"
MATERIAL"CHIP"
PACK_TYPE"0402"
PART_NUMBER"G21796-010"
TOLERANCE"1%"
VALUE"100.0K"
LOCATION"R25W142"
SEC"1"
SEC_TYPE"0402"
CDS_LIB"mstr_discrete"
CDS_LOCATION"R25W142";
"A"
$PN"1"74;
"B"
$PN"2"2;
%"GND"
"1","(-4700,1750)","0","mstr_symbols","I157";
;
CDS_LIB"mstr_symbols"
SIZE"1B"
VOLTAGE"0.0V"
BODY_TYPE"PLUMBING"
HDL_POWER"GND";
"A\NAC"2;
%"RES"
"1","(1500,3400)","0","mstr_discrete","I159";
;
CDS_SEC"1"
CDS_LOCATION"R25W143"
LOCATION"R25W143"
PACK_TYPE"0402"
TOLERANCE"5%"
WATTAGE"1/16W"
PART_NUMBER"G21497-005"
MATERIAL"CHIP"
VALUE"0.0"
CDS_LIB"mstr_discrete"
ROOM"DEBUG"
SEC_TYPE"0402"
SEC"1";
"B"
$PN"2"86;
"A"
$PN"1"85;
%"CAP_A"
"1","(1450,2150)","0","dev_discrete","I160";
;
LOCATION"C25W9"
VALUE"0.1UF"
VOLTAGE"16V"
TOLERANCE"10%"
MATERIAL"X7R"
PART_NUMBER"A36096-030"
PACK_TYPE"0402V"
CDS_LOCATION"C25W9"
SEC"1"
SEC_TYPE"0402V"
CDS_SEC"1"
CDS_LIB"dev_discrete"
BOM_COST"PROC_SIDEBAND"
ROOM"PROC_SIDEBAND";
"B"
$PN"2"15;
"A"
$PN"1"33;
%"CAP_A"
"1","(2000,2300)","1","dev_discrete","I161";
;
PACK_TYPE"0402V"
LOCATION"C25W7"
VALUE"0.1UF"
VOLTAGE"16V"
PART_NUMBER"A36096-030"
TOLERANCE"10%"
MATERIAL"X7R"
CDS_LOCATION"C25W7"
SEC"1"
SEC_TYPE"0402V"
CDS_SEC"1"
CDS_LIB"dev_discrete"
BOM_COST"PROC_SIDEBAND"
ROOM"PROC_SIDEBAND";
"B"
$PN"2"4;
"A"
$PN"1"33;
%"CAP_A"
"1","(2000,1950)","1","dev_discrete","I162";
;
PART_NUMBER"A36096-030"
LOCATION"C25W8"
VALUE"0.1UF"
PACK_TYPE"0402V"
VOLTAGE"16V"
TOLERANCE"10%"
MATERIAL"X7R"
CDS_LOCATION"C25W8"
SEC"1"
SEC_TYPE"0402V"
CDS_SEC"1"
CDS_LIB"dev_discrete"
BOM_COST"PROC_SIDEBAND"
ROOM"PROC_SIDEBAND";
"B"
$PN"2"5;
"A"
$PN"1"15;
%"RES"
"2","(-4750,1300)","0","mstr_discrete","I164";
;
CDS_SEC"1"
VALUE"100.0K"
TOLERANCE"1%"
WATTAGE"1/16W"
LOCATION"R25W157"
PACK_TYPE"0402"
PART_NUMBER"G21796-010"
MATERIAL"CHIP"
CDS_LIB"mstr_discrete"
SEC_TYPE"0402"
SEC"1"
CDS_LOCATION"R25W157";
"A"
$PN"1"78;
"B"
$PN"2"3;
%"GND"
"1","(-4750,1100)","0","mstr_symbols","I165";
;
VOLTAGE"0.0V"
SIZE"1B"
CDS_LIB"mstr_symbols"
BODY_TYPE"PLUMBING"
HDL_POWER"GND";
"A\NAC"3;
%"RES"
"1","(-4150,3100)","0","mstr_discrete","I173";
;
PACK_TYPE"0402"
MATERIAL"CHIP"
PART_NUMBER"G21497-005"
VALUE"0.0"
TOLERANCE"5%"
WATTAGE"1/16W"
LOCATION"R25W181"
CDS_SEC"1"
CDS_LOCATION"R25W181"
CDS_LIB"mstr_discrete"
ROOM"DEBUG"
SEC_TYPE"0402"
SEC"1";
"B"
$PN"2"65;
"A"
$PN"1"68;
%"W_VCC_CIRCLE"
"1","(2450,2400)","0","w_power","I20";
;
HDL_POWER"VCC_ADCAV3V3"
CDS_LMAN_SYM_OUTLINE"-100,100,100,-100"
CDS_LIB"w_power"
BODY_TYPE"PLUMBING";
"VCC_CIRCLE \B"4;
%"RES"
"1","(1000,4200)","0","mstr_discrete","I21";
;
PACK_TYPE"0402"
TOLERANCE"1.0%"
PART_NUMBER"G21796-250"
WATTAGE"1/16W"
MATERIAL"CHIP"
VALUE"22.1"
LOCATION"R25W90"
CDS_LOCATION"R25W90"
CDS_SEC"1"
ROOM"BMC"
BOM_COST"SM_CONTROLLER"
SEC"1"
SEC_TYPE"0402"
CDS_LIB"mstr_discrete";
"B"
$PN"2"20;
"A"
$PN"1"46;
%"RES"
"1","(1000,4150)","0","mstr_discrete","I22";
;
WATTAGE"1/16W"
LOCATION"R25W89"
PACK_TYPE"0402"
PART_NUMBER"G21796-250"
TOLERANCE"1.0%"
MATERIAL"CHIP"
VALUE"22.1"
CDS_LOCATION"R25W89"
CDS_SEC"1"
SEC"1"
SEC_TYPE"0402"
CDS_LIB"mstr_discrete"
ROOM"BMC"
BOM_COST"SM_CONTROLLER";
"B"
$PN"2"87;
"A"
$PN"1"47;
%"RES"
"1","(800,4000)","0","mstr_discrete","I23";
;
MATERIAL"CHIP"
LOCATION"R25W85"
WATTAGE"1/16W"
TOLERANCE"1.0%"
PART_NUMBER"G21796-250"
VALUE"22.1"
PACK_TYPE"0402"
CDS_SEC"1"
ROOM"BMC"
CDS_LIB"mstr_discrete"
SEC"1"
SEC_TYPE"0402"
BOM_COST"SM_CONTROLLER"
CDS_LOCATION"R25W85";
"B"
$PN"2"19;
"A"
$PN"1"48;
%"RES"
"1","(800,3750)","0","mstr_discrete","I24";
;
WATTAGE"1/16W"
LOCATION"R25W86"
PART_NUMBER"G21796-250"
TOLERANCE"1.0%"
PACK_TYPE"0402"
MATERIAL"CHIP"
VALUE"22.1"
CDS_LOCATION"R25W86"
CDS_SEC"1"
SEC"1"
SEC_TYPE"0402"
CDS_LIB"mstr_discrete"
ROOM"BMC"
BOM_COST"SM_CONTROLLER";
"B"
$PN"2"83;
"A"
$PN"1"13;
%"RES"
"1","(800,3800)","0","mstr_discrete","I25";
;
MATERIAL"CHIP"
PART_NUMBER"G21796-250"
WATTAGE"1/16W"
TOLERANCE"1.0%"
PACK_TYPE"0402"
VALUE"22.1"
LOCATION"R25W87"
CDS_SEC"1"
ROOM"BMC"
BOM_COST"SM_CONTROLLER"
SEC"1"
SEC_TYPE"0402"
CDS_LIB"mstr_discrete"
CDS_LOCATION"R25W87";
"B"
$PN"2"82;
"A"
$PN"1"84;
%"GND"
"1","(2450,1800)","2","mstr_symbols","I37";
;
VOLTAGE"0.0V"
SIZE"1B"
CDS_LIB"mstr_symbols"
BODY_TYPE"PLUMBING"
HDL_POWER"GND";
"A\NAC"5;
%"GND"
"1","(900,1750)","0","mstr_symbols","I41";
;
CDS_LIB"mstr_symbols"
VOLTAGE"0.0V"
SIZE"1B"
BODY_TYPE"PLUMBING"
HDL_POWER"GND";
"A\NAC"6;
%"RES"
"2","(-3600,4950)","0","mstr_discrete","I42";
;
CDS_SEC"1"
LOCATION"R25W79"
VALUE"10.0K"
PART_NUMBER"G21796-016"
PACK_TYPE"0402"
WATTAGE"1/16W"
MATERIAL"CHIP"
TOLERANCE"1%"
CDS_LIB"mstr_discrete"
BOM_COST"SM_CONTROLLER"
SEC_TYPE"0402"
SEC"1"
ROOM"BMC"
CDS_LOCATION"R25W79";
"A"
$PN"1"7;
"B"
$PN"2"52;
%"RES"
"2","(-3900,4950)","0","mstr_discrete","I43";
;
CDS_SEC"1"
PACK_TYPE"0402"
LOCATION"R25W80"
WATTAGE"1/16W"
TOLERANCE"1%"
PART_NUMBER"G21796-016"
MATERIAL"CHIP"
VALUE"10.0K"
CDS_LOCATION"R25W80"
ROOM"BMC"
SEC"1"
SEC_TYPE"0402"
BOM_COST"SM_CONTROLLER"
CDS_LIB"mstr_discrete";
"A"
$PN"1"7;
"B"
$PN"2"53;
%"P3V3_STBY"
"1","(-3900,5250)","0","mstr_symbols","I44";
;
VOLTAGE"3.3V"
CDS_LIB"mstr_symbols"
SIZE"1B"
BODY_TYPE"PLUMBING"
HDL_POWER"P3V3_STBY";
"G\NAC"7;
%"RES"
"2","(-3500,1950)","0","mstr_discrete","I61";
;
CDS_SEC"1"
PART_NUMBER"G21796-010"
PACK_TYPE"0402"
WATTAGE"1/16W"
MATERIAL"CHIP"
VALUE"100.0K"
LOCATION"R1U1"
TOLERANCE"1%"
CDS_LIB"mstr_discrete"
CDS_LOCATION"R1U1"
SEC"1"
SEC_TYPE"0402";
"A"
$PN"1"75;
"B"
$PN"2"8;
%"RES"
"2","(-3800,1950)","0","mstr_discrete","I62";
;
CDS_SEC"1"
PACK_TYPE"0402"
PART_NUMBER"G21796-010"
VALUE"100.0K"
TOLERANCE"1%"
MATERIAL"CHIP"
WATTAGE"1/16W"
LOCATION"R1U2"
CDS_LIB"mstr_discrete"
CDS_LOCATION"R1U2"
SEC_TYPE"0402"
SEC"1";
"A"
$PN"1"76;
"B"
$PN"2"9;
%"GND"
"1","(-3500,1750)","0","mstr_symbols","I63";
;
SIZE"1B"
VOLTAGE"0.0V"
CDS_LIB"mstr_symbols"
BODY_TYPE"PLUMBING"
HDL_POWER"GND";
"A\NAC"8;
%"GND"
"1","(-3800,1750)","0","mstr_symbols","I64";
;
SIZE"1B"
CDS_LIB"mstr_symbols"
VOLTAGE"0.0V"
BODY_TYPE"PLUMBING"
HDL_POWER"GND";
"A\NAC"9;
%"RES"
"2","(-4100,1950)","0","mstr_discrete","I65";
;
CDS_SEC"1"
PACK_TYPE"0402"
TOLERANCE"1%"
MATERIAL"CHIP"
PART_NUMBER"G21796-010"
WATTAGE"1/16W"
LOCATION"R1U4"
VALUE"100.0K"
CDS_LIB"mstr_discrete"
CDS_LOCATION"R1U4"
SEC"1"
SEC_TYPE"0402";
"A"
$PN"1"77;
"B"
$PN"2"10;
%"RES"
"2","(-4400,1950)","0","mstr_discrete","I66";
;
CDS_SEC"1"
TOLERANCE"1%"
MATERIAL"CHIP"
WATTAGE"1/16W"
PACK_TYPE"0402"
PART_NUMBER"G21796-010"
LOCATION"R1U5"
VALUE"100.0K"
CDS_LIB"mstr_discrete"
CDS_LOCATION"R1U5"
SEC_TYPE"0402"
SEC"1";
"A"
$PN"1"79;
"B"
$PN"2"11;
%"GND"
"1","(-4100,1750)","0","mstr_symbols","I67";
;
SIZE"1B"
VOLTAGE"0.0V"
CDS_LIB"mstr_symbols"
BODY_TYPE"PLUMBING"
HDL_POWER"GND";
"A\NAC"10;
%"GND"
"1","(-4400,1750)","0","mstr_symbols","I68";
;
SIZE"1B"
VOLTAGE"0.0V"
CDS_LIB"mstr_symbols"
BODY_TYPE"PLUMBING"
HDL_POWER"GND";
"A\NAC"11;
%"RES"
"2","(-150,1950)","0","mstr_discrete","I75";
;
CDS_SEC"1"
CDS_LOCATION"R2N13"
PART_NUMBER"G21796-016"
VALUE"10.0K"
MATERIAL"CHIP"
LOCATION"R2N13"
TOLERANCE"1%"
PACK_TYPE"0402"
WATTAGE"1/16W"
CDS_LIB"mstr_discrete"
ROOM"BMC"
BOM_COST"SM_CONTROLLER"
SEC"1"
SEC_TYPE"0402";
"A"
$PN"1"31;
"B"
$PN"2"12;
%"GND"
"1","(-150,1750)","0","mstr_symbols","I76";
;
CDS_LIB"mstr_symbols"
SIZE"1B"
VOLTAGE"0.0V"
BODY_TYPE"PLUMBING"
HDL_POWER"GND";
"A\NAC"12;
%"RES"
"1","(1000,4400)","0","mstr_discrete","I8";
;
PART_NUMBER"G21796-250"
MATERIAL"CHIP"
PACK_TYPE"0402"
VALUE"22.1"
WATTAGE"1/16W"
TOLERANCE"1.0%"
LOCATION"R25W88"
CDS_LOCATION"R25W88"
CDS_SEC"1"
SEC"1"
SEC_TYPE"0402"
ROOM"BMC"
CDS_LIB"mstr_discrete"
BOM_COST"SM_CONTROLLER";
"B"
$PN"2"21;
"A"
$PN"1"43;
END.
